;LEADER: 12 
;HEADER: 
;CODE  : ASCII 
;FILE  : 9332_F0TG_MB_C_V02_0417_0820-bd-1-6.drl for backdrilling ... from layer TOP to layer GND2
;DESIGN: 9332_F0TG_MB_C_V02_0417_0820.brd
;MUST-NOT-CUT-LAYER = IN3,  MAX_DRILL_DEPTH = 30.80 MILS,  MFG_STUB_LENGTH = 0.00 MILS
;   BackdrillSize 1. = 17.000000 Tolerance = +0.000000/-0.000000 NON_PLATED MILS Quantity = 240
%
G90
X0570309Y1602380
R08X-0012060
X0642669Y1602380
R05X-0012060
X0461769Y1602380
X0566909Y1602380
X0554849Y1602380
R07X-0012060
X0639269Y1602380
R05X-0012060
X0458369Y1602380
X0570309Y1614292
R08X-0012060
X0642669Y1614292
R05X-0012060
X0461769Y1614292
X0566909Y1614292
X0554849Y1614292
R07X-0012060
X0639269Y1614292
R05X-0012060
X0458369Y1614292
X0306136Y1614292
X0294076Y1614292
R07X-0012060
X0378496Y1614292
R05X-0012060
X0197596Y1614292
X0302736Y1614292
X0290676Y1614292
R07X-0012060
X0375096Y1614292
R05X-0012060
X0194196Y1614292
X1578183Y1635380
R08X-0012060
X1650543Y1635380
R05X-0012060
X1469643Y1635380
X1574783Y1635380
X1562723Y1635380
R07X-0012060
X1647143Y1635380
R05X-0012060
X1466243Y1635380
X1578183Y1647292
R08X-0012060
X1650543Y1647292
R05X-0012060
X1469643Y1647292
X1574783Y1647292
X1562723Y1647292
R07X-0012060
X1647143Y1647292
R05X-0012060
X1466243Y1647292
X1314009Y1635380
R08X-0012060
X1386369Y1635380
R05X-0012060
X1205469Y1635380
X1310609Y1635380
X1298549Y1635380
R07X-0012060
X1382969Y1635380
R05X-0012060
X1202069Y1635380
X1314009Y1647292
R08X-0012060
X1386369Y1647292
R05X-0012060
X1205469Y1647292
X1310609Y1647292
X1298549Y1647292
R07X-0012060
X1382969Y1647292
R05X-0012060
X1202069Y1647292
X0154945Y1627750
X0163735Y1631969
X0154945Y1624350
X0163735Y1635369
X0035852Y0699822
R02Y-0010906
X0035852Y0667045
X0035852Y0703222
X0035852Y0692316
X0035852Y0681410
X0035852Y0670445
X0776800Y0960966
X1752942Y0960965
X0120666Y0960966
X1096808Y0960965
M30
